(kicad_pcb
	(version 20260206)
	(generator "pcbnew")
	(generator_version "10.0")
	(general
		(thickness 1.6)
		(legacy_teardrops no)
	)
	(paper "A4")
	(title_block
		(title "Bryce Canyon_SCC_16316-1_OCP.brd")
		(comment 1 "Bryce Canyon / footprints 800-808 of 1561")
	)
	(layers
		(0 "F.Cu" signal "TOP")
		(4 "In1.Cu" signal "L2GND")
		(6 "In2.Cu" signal "L3")
		(8 "In3.Cu" signal "L4VCC")
		(10 "In4.Cu" signal "L5VCC")
		(12 "In5.Cu" signal "L6")
		(14 "In6.Cu" signal "L7GND")
		(2 "B.Cu" signal "BOTTOM")
		(9 "F.Adhes" user "F.Adhesive")
		(11 "B.Adhes" user "B.Adhesive")
		(13 "F.Paste" user "Package Geometry/Pastemask Top")
		(15 "B.Paste" user "Package Geometry/Pastemask Bottom")
		(5 "F.SilkS" user "Ref Des/Silkscreen Top")
		(7 "B.SilkS" user "Ref Des/Silkscreen Bottom")
		(1 "F.Mask" user "Board Geometry/Soldermask Top")
		(3 "B.Mask" user "Board Geometry/Soldermask Bottom")
		(17 "Dwgs.User" user "User.Drawings")
		(19 "Cmts.User" user "User.Comments")
		(21 "Eco1.User" user "User.Eco1")
		(23 "Eco2.User" user "User.Eco2")
		(25 "Edge.Cuts" user "Board Geometry/Outline")
		(27 "Margin" user)
		(31 "F.CrtYd" user "Package Geometry/Place Bound Top")
		(29 "B.CrtYd" user "Package Geometry/Place Bound Bottom")
		(35 "F.Fab" user "Ref Des/Assembly Top")
		(33 "B.Fab" user "Ref Des/Assembly Bottom")
	)
	(footprint ""
		(layer "B.Cu")
		(at 170.914568 -49.71161 90)
		(property "Reference" "C495"
			(at 0 0 90)
			(layer "B.SilkS")
			(hide yes)
			(effects
				(font
					(size 1.27 1.27)
				)
				(justify mirror)
			)
		)
		(property "Value" "SC1KP50V2KX-1GP"
			(at -1.1811 -2.7051 90)
			(unlocked yes)
			(layer "B.Fab")
			(hide yes)
			(effects
				(font
					(size 1.016 1.016)
					(thickness 0.1524)
				)
				(justify mirror)
			)
		)
		(property "Device Type" "C402H22"
			(at -1.1811 -4.2291 90)
			(unlocked yes)
			(layer "B.Fab")
			(hide yes)
			(effects
				(font
					(size 1.016 1.016)
					(thickness 0.1524)
				)
				(justify mirror)
			)
		)
		(duplicate_pad_numbers_are_jumpers no)
		(fp_rect
			(start 0.4318 0.9525)
			(end -0.4318 -0.9525)
			(stroke
				(width 0)
				(type default)
			)
			(fill no)
			(layer "B.CrtYd")
		)
		(fp_rect
			(start 0.4318 0.9525)
			(end -0.4318 -0.9525)
			(stroke
				(width 0)
				(type default)
			)
			(fill no)
			(layer "B.Fab")
		)
		(pad "1" smd custom
			(at 0 -0.4445 270)
			(size 0.1524 0.1524)
			(layers "B.Cu" "B.Mask" "B.Paste")
			(net "P1V8_C")
			(options
				(clearance outline)
				(anchor circle)
			)
			(primitives
				(gr_poly
					(pts
						(arc
							(start 0.3048 0.2032)
							(mid 0.275042 0.275042)
							(end 0.2032 0.3048)
						)
						(arc
							(start -0.2032 0.3048)
							(mid -0.275042 0.275042)
							(end -0.3048 0.2032)
						)
						(arc
							(start -0.3048 -0.2032)
							(mid -0.275042 -0.275042)
							(end -0.2032 -0.3048)
						)
						(arc
							(start 0.2032 -0.3048)
							(mid 0.275042 -0.275042)
							(end 0.3048 -0.2032)
						)
					)
					(width 0)
					(fill yes)
				)
			)
		)
		(pad "2" smd custom
			(at 0 0.4445 270)
			(size 0.1524 0.1524)
			(layers "B.Cu" "B.Mask" "B.Paste")
			(net "GND")
			(options
				(clearance outline)
				(anchor circle)
			)
			(primitives
				(gr_poly
					(pts
						(arc
							(start 0.3048 0.2032)
							(mid 0.275042 0.275042)
							(end 0.2032 0.3048)
						)
						(arc
							(start -0.2032 0.3048)
							(mid -0.275042 0.275042)
							(end -0.3048 0.2032)
						)
						(arc
							(start -0.3048 -0.2032)
							(mid -0.275042 -0.275042)
							(end -0.2032 -0.3048)
						)
						(arc
							(start 0.2032 -0.3048)
							(mid 0.275042 -0.275042)
							(end 0.3048 -0.2032)
						)
					)
					(width 0)
					(fill yes)
				)
			)
		)
	)
	(footprint ""
		(layer "B.Cu")
		(at 116.7003 -64.4779)
		(property "Reference" "C174"
			(at 0 0 0)
			(layer "B.SilkS")
			(hide yes)
			(effects
				(font
					(size 1.27 1.27)
				)
				(justify mirror)
			)
		)
		(property "Value" "SCD1U6D3V1KX-GP"
			(at 2.8321 -1.7399 0)
			(unlocked yes)
			(layer "B.Fab")
			(hide yes)
			(effects
				(font
					(size 1.016 1.016)
					(thickness 0.1524)
				)
				(justify mirror)
			)
		)
		(property "Device Type" "C0201H13"
			(at 2.8321 -3.2639 0)
			(unlocked yes)
			(layer "B.Fab")
			(hide yes)
			(effects
				(font
					(size 1.016 1.016)
					(thickness 0.1524)
				)
				(justify mirror)
			)
		)
		(duplicate_pad_numbers_are_jumpers no)
		(fp_rect
			(start 0.2794 0.6477)
			(end -0.2794 -0.6477)
			(stroke
				(width 0)
				(type default)
			)
			(fill no)
			(layer "B.CrtYd")
		)
		(fp_rect
			(start 0.2794 0.6477)
			(end -0.2794 -0.6477)
			(stroke
				(width 0)
				(type default)
			)
			(fill no)
			(layer "B.Fab")
		)
		(pad "1" smd custom
			(at 0 -0.2794 180)
			(size 0.0762 0.0762)
			(layers "B.Cu" "B.Mask" "B.Paste")
			(net "P0V9")
			(options
				(clearance outline)
				(anchor circle)
			)
			(primitives
				(gr_poly
					(pts
						(arc
							(start 0.1524 0.127)
							(mid 0.137521 0.162921)
							(end 0.1016 0.1778)
						)
						(arc
							(start -0.1016 0.1778)
							(mid -0.137521 0.162921)
							(end -0.1524 0.127)
						)
						(arc
							(start -0.1524 -0.127)
							(mid -0.137521 -0.162921)
							(end -0.1016 -0.1778)
						)
						(arc
							(start 0.1016 -0.1778)
							(mid 0.137521 -0.162921)
							(end 0.1524 -0.127)
						)
					)
					(width 0)
					(fill yes)
				)
			)
		)
		(pad "2" smd custom
			(at 0 0.2794 180)
			(size 0.0762 0.0762)
			(layers "B.Cu" "B.Mask" "B.Paste")
			(net "GND")
			(options
				(clearance outline)
				(anchor circle)
			)
			(primitives
				(gr_poly
					(pts
						(arc
							(start 0.1524 0.127)
							(mid 0.137521 0.162921)
							(end 0.1016 0.1778)
						)
						(arc
							(start -0.1016 0.1778)
							(mid -0.137521 0.162921)
							(end -0.1524 0.127)
						)
						(arc
							(start -0.1524 -0.127)
							(mid -0.137521 -0.162921)
							(end -0.1016 -0.1778)
						)
						(arc
							(start 0.1016 -0.1778)
							(mid 0.137521 -0.162921)
							(end 0.1524 -0.127)
						)
					)
					(width 0)
					(fill yes)
				)
			)
		)
	)
	(footprint ""
		(layer "B.Cu")
		(at 133.223 -85.217)
		(property "Reference" "TP16"
			(at 0 0 0)
			(layer "B.SilkS")
			(hide yes)
			(effects
				(font
					(size 1.27 1.27)
				)
				(justify mirror)
			)
		)
		(property "Value" "TPAD28-2-GP"
			(at 0.0127 -1.6637 0)
			(unlocked yes)
			(layer "B.Fab")
			(hide yes)
			(effects
				(font
					(size 1.016 1.016)
					(thickness 0.1524)
				)
				(justify mirror)
			)
		)
		(property "Device Type" "TPAD28"
			(at 0.0127 -3.1877 0)
			(unlocked yes)
			(layer "B.Fab")
			(hide yes)
			(effects
				(font
					(size 1.016 1.016)
					(thickness 0.1524)
				)
				(justify mirror)
			)
		)
		(duplicate_pad_numbers_are_jumpers no)
		(fp_poly
			(pts
				(arc
					(start 0.3556 0)
					(mid -0.3556 0)
					(end 0.3556 0)
				)
			)
			(stroke
				(width 0)
				(type default)
			)
			(fill no)
			(layer "B.CrtYd")
		)
		(fp_poly
			(pts
				(arc
					(start 0.6096 0)
					(mid -0.6096 0)
					(end 0.6096 0)
				)
			)
			(stroke
				(width 0)
				(type default)
			)
			(fill no)
			(layer "B.Fab")
		)
		(pad "1" smd circle
			(at 0 0 180)
			(size 0.7112 0.7112)
			(layers "B.Cu" "B.Mask" "B.Paste")
			(net "EXP_I2C_SCL11")
		)
	)
	(footprint ""
		(layer "B.Cu")
		(at 183.477408 -33.53435 -90)
		(property "Reference" "C472"
			(at 0 0 90)
			(layer "B.SilkS")
			(hide yes)
			(effects
				(font
					(size 1.27 1.27)
				)
				(justify mirror)
			)
		)
		(property "Value" "SCD1U6D3V1KX-GP"
			(at 2.8321 -1.7399 270)
			(unlocked yes)
			(layer "B.Fab")
			(hide yes)
			(effects
				(font
					(size 1.016 1.016)
					(thickness 0.1524)
				)
				(justify mirror)
			)
		)
		(property "Device Type" "C0201H13"
			(at 2.8321 -3.2639 270)
			(unlocked yes)
			(layer "B.Fab")
			(hide yes)
			(effects
				(font
					(size 1.016 1.016)
					(thickness 0.1524)
				)
				(justify mirror)
			)
		)
		(duplicate_pad_numbers_are_jumpers no)
		(fp_rect
			(start 0.2794 0.6477)
			(end -0.2794 -0.6477)
			(stroke
				(width 0)
				(type default)
			)
			(fill no)
			(layer "B.CrtYd")
		)
		(fp_rect
			(start 0.2794 0.6477)
			(end -0.2794 -0.6477)
			(stroke
				(width 0)
				(type default)
			)
			(fill no)
			(layer "B.Fab")
		)
		(pad "1" smd custom
			(at 0 -0.2794 90)
			(size 0.0762 0.0762)
			(layers "B.Cu" "B.Mask" "B.Paste")
			(net "P1V8_C")
			(options
				(clearance outline)
				(anchor circle)
			)
			(primitives
				(gr_poly
					(pts
						(arc
							(start 0.1524 0.127)
							(mid 0.137521 0.162921)
							(end 0.1016 0.1778)
						)
						(arc
							(start -0.1016 0.1778)
							(mid -0.137521 0.162921)
							(end -0.1524 0.127)
						)
						(arc
							(start -0.1524 -0.127)
							(mid -0.137521 -0.162921)
							(end -0.1016 -0.1778)
						)
						(arc
							(start 0.1016 -0.1778)
							(mid 0.137521 -0.162921)
							(end 0.1524 -0.127)
						)
					)
					(width 0)
					(fill yes)
				)
			)
		)
		(pad "2" smd custom
			(at 0 0.2794 90)
			(size 0.0762 0.0762)
			(layers "B.Cu" "B.Mask" "B.Paste")
			(net "GND")
			(options
				(clearance outline)
				(anchor circle)
			)
			(primitives
				(gr_poly
					(pts
						(arc
							(start 0.1524 0.127)
							(mid 0.137521 0.162921)
							(end 0.1016 0.1778)
						)
						(arc
							(start -0.1016 0.1778)
							(mid -0.137521 0.162921)
							(end -0.1524 0.127)
						)
						(arc
							(start -0.1524 -0.127)
							(mid -0.137521 -0.162921)
							(end -0.1016 -0.1778)
						)
						(arc
							(start 0.1016 -0.1778)
							(mid 0.137521 -0.162921)
							(end 0.1524 -0.127)
						)
					)
					(width 0)
					(fill yes)
				)
			)
		)
	)
	(footprint ""
		(layer "B.Cu")
		(at 106.3498 -44.2214 180)
		(property "Reference" "C75"
			(at 0 0 0)
			(layer "B.SilkS")
			(hide yes)
			(effects
				(font
					(size 1.27 1.27)
				)
				(justify mirror)
			)
		)
		(property "Value" "SCD01U16V1KX-GP"
			(at 2.8321 -1.7399 180)
			(unlocked yes)
			(layer "B.Fab")
			(hide yes)
			(effects
				(font
					(size 1.016 1.016)
					(thickness 0.1524)
				)
				(justify mirror)
			)
		)
		(property "Device Type" "C0201H13"
			(at 2.8321 -3.2639 180)
			(unlocked yes)
			(layer "B.Fab")
			(hide yes)
			(effects
				(font
					(size 1.016 1.016)
					(thickness 0.1524)
				)
				(justify mirror)
			)
		)
		(duplicate_pad_numbers_are_jumpers no)
		(fp_rect
			(start 0.2794 0.6477)
			(end -0.2794 -0.6477)
			(stroke
				(width 0)
				(type default)
			)
			(fill no)
			(layer "B.CrtYd")
		)
		(fp_rect
			(start 0.2794 0.6477)
			(end -0.2794 -0.6477)
			(stroke
				(width 0)
				(type default)
			)
			(fill no)
			(layer "B.Fab")
		)
		(pad "1" smd custom
			(at 0 -0.2794)
			(size 0.0762 0.0762)
			(layers "B.Cu" "B.Mask" "B.Paste")
			(net "PHY_DPB_TO_SCC_22_DP")
			(options
				(clearance outline)
				(anchor circle)
			)
			(primitives
				(gr_poly
					(pts
						(arc
							(start 0.1524 0.127)
							(mid 0.137521 0.162921)
							(end 0.1016 0.1778)
						)
						(arc
							(start -0.1016 0.1778)
							(mid -0.137521 0.162921)
							(end -0.1524 0.127)
						)
						(arc
							(start -0.1524 -0.127)
							(mid -0.137521 -0.162921)
							(end -0.1016 -0.1778)
						)
						(arc
							(start 0.1016 -0.1778)
							(mid 0.137521 -0.162921)
							(end 0.1524 -0.127)
						)
					)
					(width 0)
					(fill yes)
				)
			)
		)
		(pad "2" smd custom
			(at 0 0.2794)
			(size 0.0762 0.0762)
			(layers "B.Cu" "B.Mask" "B.Paste")
			(net "PHY_DPB_TO_SCC_C_22_DP")
			(options
				(clearance outline)
				(anchor circle)
			)
			(primitives
				(gr_poly
					(pts
						(arc
							(start 0.1524 0.127)
							(mid 0.137521 0.162921)
							(end 0.1016 0.1778)
						)
						(arc
							(start -0.1016 0.1778)
							(mid -0.137521 0.162921)
							(end -0.1524 0.127)
						)
						(arc
							(start -0.1524 -0.127)
							(mid -0.137521 -0.162921)
							(end -0.1016 -0.1778)
						)
						(arc
							(start 0.1016 -0.1778)
							(mid 0.137521 -0.162921)
							(end 0.1524 -0.127)
						)
					)
					(width 0)
					(fill yes)
				)
			)
		)
	)
	(footprint ""
		(layer "B.Cu")
		(at 175.7045 -60.063126 -90)
		(property "Reference" "R402"
			(at 0 0 90)
			(layer "B.SilkS")
			(hide yes)
			(effects
				(font
					(size 1.27 1.27)
				)
				(justify mirror)
			)
		)
		(property "Value" "0R2J-2-GP"
			(at -0.064008 -3.993896 270)
			(unlocked yes)
			(layer "B.Fab")
			(hide yes)
			(effects
				(font
					(size 1.016 1.016)
					(thickness 0.1524)
				)
				(justify mirror)
			)
		)
		(property "Device Type" "R402H16"
			(at -0.064008 -5.517896 270)
			(unlocked yes)
			(layer "B.Fab")
			(hide yes)
			(effects
				(font
					(size 1.016 1.016)
					(thickness 0.1524)
				)
				(justify mirror)
			)
		)
		(duplicate_pad_numbers_are_jumpers no)
		(fp_line
			(start -0.508 -0.9398)
			(end 0.508 -0.9398)
			(stroke
				(width 0.1524)
				(type default)
			)
			(layer "B.SilkS")
		)
		(fp_line
			(start 0.508 -0.9398)
			(end 0.508 0.9398)
			(stroke
				(width 0.1524)
				(type default)
			)
			(layer "B.SilkS")
		)
		(fp_rect
			(start 0.508 0.9398)
			(end -0.508 -0.9398)
			(stroke
				(width 0)
				(type default)
			)
			(fill no)
			(layer "B.CrtYd")
		)
		(fp_rect
			(start 0.508 0.9398)
			(end -0.508 -0.9398)
			(stroke
				(width 0)
				(type default)
			)
			(fill no)
			(layer "B.Fab")
		)
		(pad "1" smd custom
			(at 0 -0.4445 90)
			(size 0.1397 0.1397)
			(layers "B.Cu" "B.Mask" "B.Paste")
			(net "SCC_FULL_PGOOD")
			(options
				(clearance outline)
				(anchor circle)
			)
			(primitives
				(gr_poly
					(pts
						(arc
							(start -0.1778 0.2794)
							(mid -0.249642 0.249642)
							(end -0.2794 0.1778)
						)
						(arc
							(start -0.2794 -0.1778)
							(mid -0.249642 -0.249642)
							(end -0.1778 -0.2794)
						)
						(arc
							(start 0.1778 -0.2794)
							(mid 0.249642 -0.249642)
							(end 0.2794 -0.1778)
						)
						(arc
							(start 0.2794 0.1778)
							(mid 0.249642 0.249642)
							(end 0.1778 0.2794)
						)
					)
					(width 0)
					(fill yes)
				)
			)
		)
		(pad "2" smd custom
			(at 0 0.4445 90)
			(size 0.1397 0.1397)
			(layers "B.Cu" "B.Mask" "B.Paste")
			(net "SCC_FULL_PGOOD_SENSE")
			(options
				(clearance outline)
				(anchor circle)
			)
			(primitives
				(gr_poly
					(pts
						(arc
							(start -0.1778 0.2794)
							(mid -0.249642 0.249642)
							(end -0.2794 0.1778)
						)
						(arc
							(start -0.2794 -0.1778)
							(mid -0.249642 -0.249642)
							(end -0.1778 -0.2794)
						)
						(arc
							(start 0.1778 -0.2794)
							(mid 0.249642 -0.249642)
							(end 0.2794 -0.1778)
						)
						(arc
							(start 0.2794 0.1778)
							(mid 0.249642 0.249642)
							(end 0.1778 0.2794)
						)
					)
					(width 0)
					(fill yes)
				)
			)
		)
	)
	(footprint ""
		(layer "B.Cu")
		(at 109.50067 -78.48854)
		(property "Reference" "TP42"
			(at 0 0 0)
			(layer "B.SilkS")
			(hide yes)
			(effects
				(font
					(size 1.27 1.27)
				)
				(justify mirror)
			)
		)
		(property "Value" "TPAD28-2-GP"
			(at 0.0127 -1.6637 0)
			(unlocked yes)
			(layer "B.Fab")
			(hide yes)
			(effects
				(font
					(size 1.016 1.016)
					(thickness 0.1524)
				)
				(justify mirror)
			)
		)
		(property "Device Type" "TPAD28"
			(at 0.0127 -3.1877 0)
			(unlocked yes)
			(layer "B.Fab")
			(hide yes)
			(effects
				(font
					(size 1.016 1.016)
					(thickness 0.1524)
				)
				(justify mirror)
			)
		)
		(duplicate_pad_numbers_are_jumpers no)
		(fp_poly
			(pts
				(arc
					(start 0.3556 0)
					(mid -0.3556 0)
					(end 0.3556 0)
				)
			)
			(stroke
				(width 0)
				(type default)
			)
			(fill no)
			(layer "B.CrtYd")
		)
		(fp_poly
			(pts
				(arc
					(start 0.6096 0)
					(mid -0.6096 0)
					(end 0.6096 0)
				)
			)
			(stroke
				(width 0)
				(type default)
			)
			(fill no)
			(layer "B.Fab")
		)
		(pad "1" smd circle
			(at 0 0 180)
			(size 0.7112 0.7112)
			(layers "B.Cu" "B.Mask" "B.Paste")
			(net "LSI_PROCMON")
		)
	)
	(footprint ""
		(layer "B.Cu")
		(at 109.499908 -76.499974)
		(property "Reference" "TP38"
			(at 0 0 0)
			(layer "B.SilkS")
			(hide yes)
			(effects
				(font
					(size 1.27 1.27)
				)
				(justify mirror)
			)
		)
		(property "Value" "TPAD28-2-GP"
			(at 0.0127 -1.6637 0)
			(unlocked yes)
			(layer "B.Fab")
			(hide yes)
			(effects
				(font
					(size 1.016 1.016)
					(thickness 0.1524)
				)
				(justify mirror)
			)
		)
		(property "Device Type" "TPAD28"
			(at 0.0127 -3.1877 0)
			(unlocked yes)
			(layer "B.Fab")
			(hide yes)
			(effects
				(font
					(size 1.016 1.016)
					(thickness 0.1524)
				)
				(justify mirror)
			)
		)
		(duplicate_pad_numbers_are_jumpers no)
		(fp_poly
			(pts
				(arc
					(start 0.3556 0)
					(mid -0.3556 0)
					(end 0.3556 0)
				)
			)
			(stroke
				(width 0)
				(type default)
			)
			(fill no)
			(layer "B.CrtYd")
		)
		(fp_poly
			(pts
				(arc
					(start 0.6096 0)
					(mid -0.6096 0)
					(end 0.6096 0)
				)
			)
			(stroke
				(width 0)
				(type default)
			)
			(fill no)
			(layer "B.Fab")
		)
		(pad "1" smd circle
			(at 0 0 180)
			(size 0.7112 0.7112)
			(layers "B.Cu" "B.Mask" "B.Paste")
			(net "JTAG_EXP_TDI")
		)
	)
	(footprint ""
		(layer "B.Cu")
		(at 122.4788 -61.4934 -90)
		(property "Reference" "C269"
			(at 0 0 90)
			(layer "B.SilkS")
			(hide yes)
			(effects
				(font
					(size 1.27 1.27)
				)
				(justify mirror)
			)
		)
		(property "Value" "SCD1U6D3V1KX-GP"
			(at 2.8321 -1.7399 270)
			(unlocked yes)
			(layer "B.Fab")
			(hide yes)
			(effects
				(font
					(size 1.016 1.016)
					(thickness 0.1524)
				)
				(justify mirror)
			)
		)
		(property "Device Type" "C0201H13"
			(at 2.8321 -3.2639 270)
			(unlocked yes)
			(layer "B.Fab")
			(hide yes)
			(effects
				(font
					(size 1.016 1.016)
					(thickness 0.1524)
				)
				(justify mirror)
			)
		)
		(duplicate_pad_numbers_are_jumpers no)
		(fp_rect
			(start 0.2794 0.6477)
			(end -0.2794 -0.6477)
			(stroke
				(width 0)
				(type default)
			)
			(fill no)
			(layer "B.CrtYd")
		)
		(fp_rect
			(start 0.2794 0.6477)
			(end -0.2794 -0.6477)
			(stroke
				(width 0)
				(type default)
			)
			(fill no)
			(layer "B.Fab")
		)
		(pad "1" smd custom
			(at 0 -0.2794 90)
			(size 0.0762 0.0762)
			(layers "B.Cu" "B.Mask" "B.Paste")
			(net "GB_VDDA")
			(options
				(clearance outline)
				(anchor circle)
			)
			(primitives
				(gr_poly
					(pts
						(arc
							(start 0.1524 0.127)
							(mid 0.137521 0.162921)
							(end 0.1016 0.1778)
						)
						(arc
							(start -0.1016 0.1778)
							(mid -0.137521 0.162921)
							(end -0.1524 0.127)
						)
						(arc
							(start -0.1524 -0.127)
							(mid -0.137521 -0.162921)
							(end -0.1016 -0.1778)
						)
						(arc
							(start 0.1016 -0.1778)
							(mid 0.137521 -0.162921)
							(end 0.1524 -0.127)
						)
					)
					(width 0)
					(fill yes)
				)
			)
		)
		(pad "2" smd custom
			(at 0 0.2794 90)
			(size 0.0762 0.0762)
			(layers "B.Cu" "B.Mask" "B.Paste")
			(net "GND")
			(options
				(clearance outline)
				(anchor circle)
			)
			(primitives
				(gr_poly
					(pts
						(arc
							(start 0.1524 0.127)
							(mid 0.137521 0.162921)
							(end 0.1016 0.1778)
						)
						(arc
							(start -0.1016 0.1778)
							(mid -0.137521 0.162921)
							(end -0.1524 0.127)
						)
						(arc
							(start -0.1524 -0.127)
							(mid -0.137521 -0.162921)
							(end -0.1016 -0.1778)
						)
						(arc
							(start 0.1016 -0.1778)
							(mid 0.137521 -0.162921)
							(end 0.1524 -0.127)
						)
					)
					(width 0)
					(fill yes)
				)
			)
		)
	)
)
